FILE_TYPE = MACRO_DRAWING;
SET COLOR_WIRE YELLOW;
SET COLOR_PROP ORANGE;
SET COLOR_DOT WHITE;
SET COLOR_ARC YELLOW;
SET COLOR_BODY GREEN;
SET COLOR_NOTE PURPLE;
SET PROP_DISPLAY VALUE;
SET PAGE_NUMBER P49;
FORCEADD SOCKET4677_AZIF0045P001C01CS..6
(925 2500);
FORCEPROP 1 LAST PART_NUMBER DGA^7000023
J 0
(-125 3000);
DISPLAY 0.723404 (-125 3000);
PAINT GREEN (-125 3000);
DISPLAY INVISIBLE (-125 3000);
FORCEPROP 2 LAST VALUE SOCKET4677_AZIF0045-P001C01CS
J 0
(-125 3125);
DISPLAY 1.021277 (-125 3125);
FORCEPROP 1 LAST MATERIAL IO
J 0
(-125 2925);
DISPLAY 0.723404 (-125 2925);
PAINT GREEN (-125 2925);
FORCEPROP 2 LAST PART_TYPE SMLF
J 0
(-125 3175);
DISPLAY 1.021277 (-125 3175);
FORCEPROP 1 LAST $LOCATION U1
J 0
(-125 3075);
DISPLAY 0.723404 (-125 3075);
PAINT GREEN (-125 3075);
FORCEPROP 0 LASTPIN (-275 2700) $PN AU52
J 2
(-285 2710);
DISPLAY 0.680851 (-285 2710);
PAINT MONO (-285 2710);
FORCEPROP 0 LASTPIN (-275 2250) $PN BD77
J 2
(-285 2260);
DISPLAY 0.680851 (-285 2260);
PAINT MONO (-285 2260);
FORCEPROP 0 LASTPIN (-275 2350) $PN CD69
J 2
(-285 2360);
DISPLAY 0.680851 (-285 2360);
PAINT MONO (-285 2360);
FORCEPROP 0 LASTPIN (-275 2400) $PN CG60
J 2
(-285 2410);
DISPLAY 0.680851 (-285 2410);
PAINT MONO (-285 2410);
FORCEPROP 0 LASTPIN (-275 2450) $PN CH61
J 2
(-285 2460);
DISPLAY 0.680851 (-285 2460);
PAINT MONO (-285 2460);
FORCEPROP 0 LASTPIN (-275 2500) $PN CK61
J 2
(-285 2510);
DISPLAY 0.680851 (-285 2510);
PAINT MONO (-285 2510);
FORCEPROP 0 LASTPIN (-275 2550) $PN CL60
J 2
(-285 2560);
DISPLAY 0.680851 (-285 2560);
PAINT MONO (-285 2560);
FORCEPROP 0 LASTPIN (-275 2300) $PN CL70
J 2
(-285 2310);
DISPLAY 0.680851 (-285 2310);
PAINT MONO (-285 2310);
FORCEPROP 0 LASTPIN (-275 2600) $PN CW43
J 2
(-285 2610);
DISPLAY 0.680851 (-285 2610);
PAINT MONO (-285 2610);
FORCEPROP 0 LASTPIN (-275 2750) $PN DA70
J 2
(-285 2760);
DISPLAY 0.680851 (-285 2760);
PAINT MONO (-285 2760);
FORCEPROP 0 LASTPIN (-275 2650) $PN J13
J 2
(-285 2660);
DISPLAY 0.680851 (-285 2660);
PAINT MONO (-285 2660);
FORCEPROP 1 LAST CDS_LMAN_SYM_OUTLINE -1050,400,1050,-400
J 0
(925 2500);
DISPLAY 0.468085 (925 2500);
PAINT GREEN (925 2500);
DISPLAY INVISIBLE (925 2500);
FORCEPROP 1 LAST NEEDS_NO_SIZE TRUE
J 0
(925 2500);
DISPLAY 0.723404 (925 2500);
PAINT GREEN (925 2500);
DISPLAY INVISIBLE (925 2500);
FORCEPROP 2 LAST CDS_LIB pure_quanta
J 0
(925 2500);
DISPLAY INVISIBLE (925 2500);
FORCEPROP 2 LAST CDS_LOCATION U1
J 0
(-125 3225);
DISPLAY 1.021277 (-125 3225);
DISPLAY INVISIBLE (-125 3225);
FORCEPROP 0 LAST $SEC 6
J 0
(-125 3225);
DISPLAY 0.680851 (-125 3225);
PAINT MONO (-125 3225);
DISPLAY INVISIBLE (-125 3225);
FORCEPROP 0 LAST CDS_SEC 6
J 0
(-125 3225);
DISPLAY 1.021277 (-125 3225);
DISPLAY INVISIBLE (-125 3225);
FORCEPROP 1 LAST PATH I2
J 0
(925 2500);
DISPLAY 0.723404 (925 2500);
PAINT GREEN (925 2500);
DISPLAY INVISIBLE (925 2500);
FORCEADD QUANTA_TITLE_BLOCK_C..1
(5425 -1725);
FORCEPROP 0 LAST CDS_CON_LAST_MODIFIED Fri Aug 25 14:00:32 2023
J 0
(3540 -1710);
PAINT MONO (3540 -1710);
DISPLAY INVISIBLE (3540 -1710);
FORCEPROP 1 LAST CUSTOM_TXT_CDS <CON_LAST_MODIFIED>
J 0
(3540 -1710);
DISPLAY 0.978723 (3540 -1710);
FORCEPROP 2 LAST CUSTOM_TXT_CDS <XR_PAGE_TITLE>
J 0
(-2465 3525);
DISPLAY 0.638298 (-2465 3525);
PAINT PINK (-2465 3525);
DISPLAY INVISIBLE (-2465 3525);
FORCEPROP 2 LAST CUSTOM_TXT_CDS <Q_NUMBER>
J 0
(4022 -1622);
DISPLAY 1.212766 (4022 -1622);
FORCEPROP 1 LAST CUSTOM_TXT_CDS <NAME_2>
J 0
(2250 -1675);
FORCEPROP 1 LAST CUSTOM_TXT_CDS <NAME_1>
J 0
(2250 -1550);
FORCEPROP 1 LAST CUSTOM_TXT_CDS <Q_PROJ>
J 0
(3043 -1623);
DISPLAY 1.212766 (3043 -1623);
FORCEPROP 1 LAST CUSTOM_TXT_CDS <Q_REV>
J 0
(5241 -1622);
DISPLAY 1.212766 (5241 -1622);
FORCEPROP 1 LAST CUSTOM_TXT_CDS <CON_PAGE_NUM> OF <CON_TOTAL_PAGES>
J 0
(4979 -1707);
DISPLAY 0.978723 (4979 -1707);
FORCEPROP 1 LAST Q_TITLE SPR CPU1 MISC:SPARE(6 OF 30)
J 0
(-3941 -1699);
DISPLAY 1.957447 (-3941 -1699);
PAINT GREEN (-3941 -1699);
FORCEPROP 1 LAST Q_DEPT 
J 1
(1662 -1676);
DISPLAY 1.957447 (1662 -1676);
PAINT GREEN (1662 -1676);
FORCEPROP 2 LAST PAGE_BORDER TRUE
J 0
(-2465 3525);
DISPLAY 0.638298 (-2465 3525);
PAINT PINK (-2465 3525);
DISPLAY INVISIBLE (-2465 3525);
FORCEPROP 1 LAST CDS_LMAN_SYM_OUTLINE -9475,6775,100,-125
J 0
(5425 -1725);
DISPLAY 0.468085 (5425 -1725);
PAINT GREEN (5425 -1725);
DISPLAY INVISIBLE (5425 -1725);
FORCEPROP 2 LAST CDS_LIB pure_quanta
J 0
(5425 -1725);
PAINT MONO (5425 -1725);
DISPLAY INVISIBLE (5425 -1725);
FORCEPROP 2 LAST CDS_XR_PAGE_TITLE CR-49 : @S9S_MB_2U_LIB.S9S_MB_2U(SCH_1):PAGE49
J 0
(-2465 3525);
DISPLAY 0.638298 (-2465 3525);
PAINT PINK (-2465 3525);
DISPLAY INVISIBLE (-2465 3525);
FORCEPROP 1 LAST COMMENT_BODY TRUE
J 0
(5437 -1738);
DISPLAY 0.978723 (5437 -1738);
PAINT GREEN (5437 -1738);
DISPLAY INVISIBLE (5437 -1738);
WIRE 16 -1 (-275 2750)(-1950 2750);
FORCEPROP 2 LAST SIG_NAME TP_CPU1_SPARE4
J 0
(-1887 2759);
DISPLAY 0.680851 (-1887 2759);
PAINT WHITE (-1887 2759);
WIRE 16 -1 (-1950 2650)(-275 2650);
FORCEPROP 2 LAST SIG_NAME TP_CPU1_PPD
J 0
(-1887 2659);
DISPLAY 0.680851 (-1887 2659);
PAINT WHITE (-1887 2659);
WIRE 16 -1 (-1950 2400)(-275 2400);
FORCEPROP 2 LAST SIG_NAME TP_CPU1_SPARE10
J 0
(-1887 2409);
DISPLAY 0.680851 (-1887 2409);
PAINT WHITE (-1887 2409);
WIRE 16 -1 (-1950 2500)(-275 2500);
FORCEPROP 2 LAST SIG_NAME TP_CPU1_SPARE8
J 0
(-1887 2509);
DISPLAY 0.680851 (-1887 2509);
PAINT WHITE (-1887 2509);
WIRE 16 -1 (-1950 2350)(-275 2350);
FORCEPROP 2 LAST SIG_NAME TP_CPU1_SPARE11
J 0
(-1887 2359);
DISPLAY 0.680851 (-1887 2359);
PAINT WHITE (-1887 2359);
WIRE 16 -1 (-1950 2700)(-275 2700);
FORCEPROP 2 LAST SIG_NAME TP_CPU1_SPARE5
J 0
(-1887 2709);
DISPLAY 0.680851 (-1887 2709);
PAINT WHITE (-1887 2709);
WIRE 16 -1 (-275 2450)(-1950 2450);
FORCEPROP 2 LAST SIG_NAME TP_CPU1_SPARE9
J 0
(-1887 2459);
DISPLAY 0.680851 (-1887 2459);
PAINT WHITE (-1887 2459);
WIRE 16 -1 (-1950 2250)(-275 2250);
FORCEPROP 2 LAST SIG_NAME TP_CPU1_SPARE13
J 0
(-1887 2259);
DISPLAY 0.680851 (-1887 2259);
PAINT WHITE (-1887 2259);
WIRE 16 -1 (-275 2600)(-1950 2600);
FORCEPROP 2 LAST SIG_NAME TP_CPU1_SPARE6
J 0
(-1887 2609);
DISPLAY 0.680851 (-1887 2609);
PAINT WHITE (-1887 2609);
WIRE 16 -1 (-1950 2550)(-275 2550);
FORCEPROP 2 LAST SIG_NAME TP_CPU1_SPARE7
J 0
(-1887 2559);
DISPLAY 0.680851 (-1887 2559);
PAINT WHITE (-1887 2559);
WIRE 16 -1 (-275 2300)(-1950 2300);
FORCEPROP 2 LAST SIG_NAME TP_CPU1_SPARE12
J 0
(-1887 2309);
DISPLAY 0.680851 (-1887 2309);
PAINT WHITE (-1887 2309);
QUIT
